(kicad_pcb
	(version 20260206)
	(generator "pcbnew")
	(generator_version "10.0")
	(general
		(thickness 1.6)
		(legacy_teardrops no)
	)
	(paper "A4")
	(title_block
		(title "12092022_DA0F0TFB6D0_F0T_FAN_BOARD_MP5048_D_brd_v02_OCP.brd")
		(comment 1 "Grand Teton / footprints 1-6 of 924")
	)
	(layers
		(0 "F.Cu" signal "TOP")
		(4 "In1.Cu" signal "GND")
		(6 "In2.Cu" signal "IN1")
		(8 "In3.Cu" signal "IN2")
		(10 "In4.Cu" signal "GND1")
		(2 "B.Cu" signal "BOTTOM")
		(9 "F.Adhes" user "F.Adhesive")
		(11 "B.Adhes" user "B.Adhesive")
		(13 "F.Paste" user "Package Geometry/Pastemask Top")
		(15 "B.Paste" user "Package Geometry/Pastemask Bottom")
		(5 "F.SilkS" user "Ref Des/Silkscreen Top")
		(7 "B.SilkS" user "Ref Des/Silkscreen Bottom")
		(1 "F.Mask" user "Board Geometry/Soldermask Top")
		(3 "B.Mask" user "Board Geometry/Soldermask Bottom")
		(17 "Dwgs.User" user "User.Drawings")
		(19 "Cmts.User" user "User.Comments")
		(21 "Eco1.User" user "User.Eco1")
		(23 "Eco2.User" user "User.Eco2")
		(25 "Edge.Cuts" user "Board Geometry/Outline")
		(27 "Margin" user)
		(31 "F.CrtYd" user "Package Geometry/Place Bound Top")
		(29 "B.CrtYd" user "Package Geometry/Place Bound Bottom")
		(35 "F.Fab" user "Ref Des/Assembly Top")
		(33 "B.Fab" user "Ref Des/Assembly Bottom")
	)
	(footprint ""
		(layer "F.Cu")
		(at 24.638 -187.452 180)
		(property "Reference" "C2084"
			(at 0 0 180)
			(layer "F.SilkS")
			(hide yes)
			(effects
				(font
					(size 1.27 1.27)
				)
			)
		)
		(property "Value" ""
			(at 0 0 180)
			(layer "F.Fab")
			(effects
				(font
					(size 1.27 1.27)
				)
			)
		)
		(duplicate_pad_numbers_are_jumpers no)
		(fp_line
			(start 0.7874 0.4064)
			(end -0.7874 0.4064)
			(stroke
				(width 0.1524)
				(type default)
			)
			(layer "F.SilkS")
		)
		(fp_line
			(start 0.7874 -0.4064)
			(end 0.7874 0.4064)
			(stroke
				(width 0.1524)
				(type default)
			)
			(layer "F.SilkS")
		)
		(fp_line
			(start -0.7874 0.4064)
			(end -0.7874 -0.4064)
			(stroke
				(width 0.1524)
				(type default)
			)
			(layer "F.SilkS")
		)
		(fp_line
			(start -0.7874 -0.4064)
			(end 0.7874 -0.4064)
			(stroke
				(width 0.1524)
				(type default)
			)
			(layer "F.SilkS")
		)
		(fp_line
			(start 0.67945 0.3048)
			(end 0.120396 0.3048)
			(stroke
				(width 0.1)
				(type default)
			)
			(layer "F.Fab")
		)
		(fp_line
			(start 0.67945 -0.3048)
			(end 0.67945 0.3048)
			(stroke
				(width 0.1)
				(type default)
			)
			(layer "F.Fab")
		)
		(fp_line
			(start 0.12065 -0.2794)
			(end 0.12065 -0.3048)
			(stroke
				(width 0.1)
				(type default)
			)
			(layer "F.Fab")
		)
		(fp_line
			(start 0.12065 -0.3048)
			(end 0.67945 -0.3048)
			(stroke
				(width 0.1)
				(type default)
			)
			(layer "F.Fab")
		)
		(fp_line
			(start 0.120396 0.3048)
			(end 0.120396 0.2794)
			(stroke
				(width 0.1)
				(type default)
			)
			(layer "F.Fab")
		)
		(fp_line
			(start 0.120396 0.2794)
			(end -0.12065 0.2794)
			(stroke
				(width 0.1)
				(type default)
			)
			(layer "F.Fab")
		)
		(fp_line
			(start -0.12065 0.3048)
			(end -0.67945 0.3048)
			(stroke
				(width 0.1)
				(type default)
			)
			(layer "F.Fab")
		)
		(fp_line
			(start -0.12065 0.2794)
			(end -0.12065 0.3048)
			(stroke
				(width 0.1)
				(type default)
			)
			(layer "F.Fab")
		)
		(fp_line
			(start -0.12065 -0.2794)
			(end 0.12065 -0.2794)
			(stroke
				(width 0.1)
				(type default)
			)
			(layer "F.Fab")
		)
		(fp_line
			(start -0.12065 -0.305054)
			(end -0.12065 -0.2794)
			(stroke
				(width 0.1)
				(type default)
			)
			(layer "F.Fab")
		)
		(fp_line
			(start -0.67945 0.3048)
			(end -0.67945 -0.305054)
			(stroke
				(width 0.1)
				(type default)
			)
			(layer "F.Fab")
		)
		(fp_line
			(start -0.67945 -0.305054)
			(end -0.12065 -0.305054)
			(stroke
				(width 0.1)
				(type default)
			)
			(layer "F.Fab")
		)
		(pad "1" smd circle
			(at -0.40005 0 180)
			(size 0 0)
			(layers "F.Cu" "F.Mask" "F.Paste")
			(net "P52V_FAN_5_BUFF_EN_R")
		)
		(pad "2" smd circle
			(at 0.40005 0 180)
			(size 0 0)
			(layers "F.Cu" "F.Mask" "F.Paste")
			(net "GND")
		)
	)
	(footprint ""
		(layer "F.Cu")
		(at 23.241 -303.53 -90)
		(property "Reference" "R5511"
			(at 0 0 270)
			(layer "F.SilkS")
			(hide yes)
			(effects
				(font
					(size 1.27 1.27)
				)
			)
		)
		(property "Value" ""
			(at 0 0 270)
			(layer "F.Fab")
			(effects
				(font
					(size 1.27 1.27)
				)
			)
		)
		(duplicate_pad_numbers_are_jumpers no)
		(fp_line
			(start -0.7874 0.4064)
			(end -0.7874 -0.4064)
			(stroke
				(width 0.1524)
				(type default)
			)
			(layer "F.SilkS")
		)
		(fp_line
			(start 0.7874 0.4064)
			(end -0.7874 0.4064)
			(stroke
				(width 0.1524)
				(type default)
			)
			(layer "F.SilkS")
		)
		(fp_line
			(start -0.7874 -0.4064)
			(end 0.7874 -0.4064)
			(stroke
				(width 0.1524)
				(type default)
			)
			(layer "F.SilkS")
		)
		(fp_line
			(start 0.7874 -0.4064)
			(end 0.7874 0.4064)
			(stroke
				(width 0.1524)
				(type default)
			)
			(layer "F.SilkS")
		)
		(fp_line
			(start -0.67945 0.3048)
			(end -0.67945 -0.305054)
			(stroke
				(width 0.1)
				(type default)
			)
			(layer "F.Fab")
		)
		(fp_line
			(start -0.12065 0.3048)
			(end -0.67945 0.3048)
			(stroke
				(width 0.1)
				(type default)
			)
			(layer "F.Fab")
		)
		(fp_line
			(start 0.120396 0.3048)
			(end 0.120396 0.2794)
			(stroke
				(width 0.1)
				(type default)
			)
			(layer "F.Fab")
		)
		(fp_line
			(start 0.67945 0.3048)
			(end 0.120396 0.3048)
			(stroke
				(width 0.1)
				(type default)
			)
			(layer "F.Fab")
		)
		(fp_line
			(start -0.12065 0.2794)
			(end -0.12065 0.3048)
			(stroke
				(width 0.1)
				(type default)
			)
			(layer "F.Fab")
		)
		(fp_line
			(start 0.120396 0.2794)
			(end -0.12065 0.2794)
			(stroke
				(width 0.1)
				(type default)
			)
			(layer "F.Fab")
		)
		(fp_line
			(start -0.12065 -0.2794)
			(end 0.12065 -0.2794)
			(stroke
				(width 0.1)
				(type default)
			)
			(layer "F.Fab")
		)
		(fp_line
			(start 0.12065 -0.2794)
			(end 0.12065 -0.3048)
			(stroke
				(width 0.1)
				(type default)
			)
			(layer "F.Fab")
		)
		(fp_line
			(start 0.12065 -0.3048)
			(end 0.67945 -0.3048)
			(stroke
				(width 0.1)
				(type default)
			)
			(layer "F.Fab")
		)
		(fp_line
			(start 0.67945 -0.3048)
			(end 0.67945 0.3048)
			(stroke
				(width 0.1)
				(type default)
			)
			(layer "F.Fab")
		)
		(fp_line
			(start -0.67945 -0.305054)
			(end -0.12065 -0.305054)
			(stroke
				(width 0.1)
				(type default)
			)
			(layer "F.Fab")
		)
		(fp_line
			(start -0.12065 -0.305054)
			(end -0.12065 -0.2794)
			(stroke
				(width 0.1)
				(type default)
			)
			(layer "F.Fab")
		)
		(pad "1" smd circle
			(at -0.40005 0 270)
			(size 0 0)
			(layers "F.Cu" "F.Mask" "F.Paste")
			(net "P3V3_AUX")
		)
		(pad "2" smd circle
			(at 0.40005 0 270)
			(size 0 0)
			(layers "F.Cu" "F.Mask" "F.Paste")
			(net "FAN_0_PWM_BUF")
		)
	)
	(footprint ""
		(layer "F.Cu")
		(at 4.826 -135.255 -90)
		(property "Reference" "R5568"
			(at 0 0 270)
			(layer "F.SilkS")
			(hide yes)
			(effects
				(font
					(size 1.27 1.27)
				)
			)
		)
		(property "Value" ""
			(at 0 0 270)
			(layer "F.Fab")
			(effects
				(font
					(size 1.27 1.27)
				)
			)
		)
		(duplicate_pad_numbers_are_jumpers no)
		(fp_line
			(start -0.7874 0.4064)
			(end -0.7874 -0.4064)
			(stroke
				(width 0.1524)
				(type default)
			)
			(layer "F.SilkS")
		)
		(fp_line
			(start 0.7874 0.4064)
			(end -0.7874 0.4064)
			(stroke
				(width 0.1524)
				(type default)
			)
			(layer "F.SilkS")
		)
		(fp_line
			(start -0.7874 -0.4064)
			(end 0.7874 -0.4064)
			(stroke
				(width 0.1524)
				(type default)
			)
			(layer "F.SilkS")
		)
		(fp_line
			(start 0.7874 -0.4064)
			(end 0.7874 0.4064)
			(stroke
				(width 0.1524)
				(type default)
			)
			(layer "F.SilkS")
		)
		(fp_line
			(start -0.67945 0.3048)
			(end -0.67945 -0.305054)
			(stroke
				(width 0.1)
				(type default)
			)
			(layer "F.Fab")
		)
		(fp_line
			(start -0.12065 0.3048)
			(end -0.67945 0.3048)
			(stroke
				(width 0.1)
				(type default)
			)
			(layer "F.Fab")
		)
		(fp_line
			(start 0.120396 0.3048)
			(end 0.120396 0.2794)
			(stroke
				(width 0.1)
				(type default)
			)
			(layer "F.Fab")
		)
		(fp_line
			(start 0.67945 0.3048)
			(end 0.120396 0.3048)
			(stroke
				(width 0.1)
				(type default)
			)
			(layer "F.Fab")
		)
		(fp_line
			(start -0.12065 0.2794)
			(end -0.12065 0.3048)
			(stroke
				(width 0.1)
				(type default)
			)
			(layer "F.Fab")
		)
		(fp_line
			(start 0.120396 0.2794)
			(end -0.12065 0.2794)
			(stroke
				(width 0.1)
				(type default)
			)
			(layer "F.Fab")
		)
		(fp_line
			(start -0.12065 -0.2794)
			(end 0.12065 -0.2794)
			(stroke
				(width 0.1)
				(type default)
			)
			(layer "F.Fab")
		)
		(fp_line
			(start 0.12065 -0.2794)
			(end 0.12065 -0.3048)
			(stroke
				(width 0.1)
				(type default)
			)
			(layer "F.Fab")
		)
		(fp_line
			(start 0.12065 -0.3048)
			(end 0.67945 -0.3048)
			(stroke
				(width 0.1)
				(type default)
			)
			(layer "F.Fab")
		)
		(fp_line
			(start 0.67945 -0.3048)
			(end 0.67945 0.3048)
			(stroke
				(width 0.1)
				(type default)
			)
			(layer "F.Fab")
		)
		(fp_line
			(start -0.67945 -0.305054)
			(end -0.12065 -0.305054)
			(stroke
				(width 0.1)
				(type default)
			)
			(layer "F.Fab")
		)
		(fp_line
			(start -0.12065 -0.305054)
			(end -0.12065 -0.2794)
			(stroke
				(width 0.1)
				(type default)
			)
			(layer "F.Fab")
		)
		(pad "1" smd circle
			(at -0.40005 0 270)
			(size 0 0)
			(layers "F.Cu" "F.Mask" "F.Paste")
			(net "SMB_PDBV_FAN_SDA")
		)
		(pad "2" smd circle
			(at 0.40005 0 270)
			(size 0 0)
			(layers "F.Cu" "F.Mask" "F.Paste")
			(net "SMB_PDBV_FAN_R_U404_SDA")
		)
	)
	(footprint ""
		(layer "F.Cu")
		(at 49.492916 -36.304474 -90)
		(property "Reference" "C2049"
			(at 0 0 270)
			(layer "F.SilkS")
			(hide yes)
			(effects
				(font
					(size 1.27 1.27)
				)
			)
		)
		(property "Value" ""
			(at 0 0 270)
			(layer "F.Fab")
			(effects
				(font
					(size 1.27 1.27)
				)
			)
		)
		(duplicate_pad_numbers_are_jumpers no)
		(fp_line
			(start -0.7874 0.4064)
			(end -0.7874 -0.4064)
			(stroke
				(width 0.1524)
				(type default)
			)
			(layer "F.SilkS")
		)
		(fp_line
			(start 0.7874 0.4064)
			(end -0.7874 0.4064)
			(stroke
				(width 0.1524)
				(type default)
			)
			(layer "F.SilkS")
		)
		(fp_line
			(start -0.7874 -0.4064)
			(end 0.7874 -0.4064)
			(stroke
				(width 0.1524)
				(type default)
			)
			(layer "F.SilkS")
		)
		(fp_line
			(start 0.7874 -0.4064)
			(end 0.7874 0.4064)
			(stroke
				(width 0.1524)
				(type default)
			)
			(layer "F.SilkS")
		)
		(fp_line
			(start -0.6858 0.3048)
			(end -0.6858 -0.3048)
			(stroke
				(width 0.1)
				(type default)
			)
			(layer "F.Fab")
		)
		(fp_line
			(start -0.1016 0.3048)
			(end -0.6858 0.3048)
			(stroke
				(width 0.1)
				(type default)
			)
			(layer "F.Fab")
		)
		(fp_line
			(start 0.1016 0.3048)
			(end 0.1016 0.2794)
			(stroke
				(width 0.1)
				(type default)
			)
			(layer "F.Fab")
		)
		(fp_line
			(start 0.6858 0.3048)
			(end 0.1016 0.3048)
			(stroke
				(width 0.1)
				(type default)
			)
			(layer "F.Fab")
		)
		(fp_line
			(start -0.1016 0.2794)
			(end -0.1016 0.3048)
			(stroke
				(width 0.1)
				(type default)
			)
			(layer "F.Fab")
		)
		(fp_line
			(start 0.1016 0.2794)
			(end -0.1016 0.2794)
			(stroke
				(width 0.1)
				(type default)
			)
			(layer "F.Fab")
		)
		(fp_line
			(start -0.1016 -0.2794)
			(end 0.1016 -0.2794)
			(stroke
				(width 0.1)
				(type default)
			)
			(layer "F.Fab")
		)
		(fp_line
			(start 0.1016 -0.2794)
			(end 0.1016 -0.3048)
			(stroke
				(width 0.1)
				(type default)
			)
			(layer "F.Fab")
		)
		(fp_line
			(start -0.6858 -0.3048)
			(end -0.1016 -0.3048)
			(stroke
				(width 0.1)
				(type default)
			)
			(layer "F.Fab")
		)
		(fp_line
			(start -0.1016 -0.3048)
			(end -0.1016 -0.2794)
			(stroke
				(width 0.1)
				(type default)
			)
			(layer "F.Fab")
		)
		(fp_line
			(start 0.1016 -0.3048)
			(end 0.6858 -0.3048)
			(stroke
				(width 0.1)
				(type default)
			)
			(layer "F.Fab")
		)
		(fp_line
			(start 0.6858 -0.3048)
			(end 0.6858 0.3048)
			(stroke
				(width 0.1)
				(type default)
			)
			(layer "F.Fab")
		)
		(pad "1" smd rect
			(at -0.40005 0 90)
			(size 0.4572 0.508)
			(layers "F.Cu" "F.Mask" "F.Paste")
			(net "GND")
		)
		(pad "2" smd rect
			(at 0.40005 0 90)
			(size 0.4572 0.508)
			(layers "F.Cu" "F.Mask" "F.Paste")
			(net "P12V_LED_FAN3")
		)
	)
	(footprint ""
		(layer "F.Cu")
		(at 2.2606 -35.796474 -90)
		(property "Reference" "C2012"
			(at 0 0 270)
			(layer "F.SilkS")
			(hide yes)
			(effects
				(font
					(size 1.27 1.27)
				)
			)
		)
		(property "Value" ""
			(at 0 0 270)
			(layer "F.Fab")
			(effects
				(font
					(size 1.27 1.27)
				)
			)
		)
		(duplicate_pad_numbers_are_jumpers no)
		(fp_line
			(start -0.7874 0.4064)
			(end -0.7874 -0.4064)
			(stroke
				(width 0.1524)
				(type default)
			)
			(layer "F.SilkS")
		)
		(fp_line
			(start 0.7874 0.4064)
			(end -0.7874 0.4064)
			(stroke
				(width 0.1524)
				(type default)
			)
			(layer "F.SilkS")
		)
		(fp_line
			(start -0.7874 -0.4064)
			(end 0.7874 -0.4064)
			(stroke
				(width 0.1524)
				(type default)
			)
			(layer "F.SilkS")
		)
		(fp_line
			(start 0.7874 -0.4064)
			(end 0.7874 0.4064)
			(stroke
				(width 0.1524)
				(type default)
			)
			(layer "F.SilkS")
		)
		(fp_line
			(start -0.6858 0.3048)
			(end -0.6858 -0.3048)
			(stroke
				(width 0.1)
				(type default)
			)
			(layer "F.Fab")
		)
		(fp_line
			(start -0.1016 0.3048)
			(end -0.6858 0.3048)
			(stroke
				(width 0.1)
				(type default)
			)
			(layer "F.Fab")
		)
		(fp_line
			(start 0.1016 0.3048)
			(end 0.1016 0.2794)
			(stroke
				(width 0.1)
				(type default)
			)
			(layer "F.Fab")
		)
		(fp_line
			(start 0.6858 0.3048)
			(end 0.1016 0.3048)
			(stroke
				(width 0.1)
				(type default)
			)
			(layer "F.Fab")
		)
		(fp_line
			(start -0.1016 0.2794)
			(end -0.1016 0.3048)
			(stroke
				(width 0.1)
				(type default)
			)
			(layer "F.Fab")
		)
		(fp_line
			(start 0.1016 0.2794)
			(end -0.1016 0.2794)
			(stroke
				(width 0.1)
				(type default)
			)
			(layer "F.Fab")
		)
		(fp_line
			(start -0.1016 -0.2794)
			(end 0.1016 -0.2794)
			(stroke
				(width 0.1)
				(type default)
			)
			(layer "F.Fab")
		)
		(fp_line
			(start 0.1016 -0.2794)
			(end 0.1016 -0.3048)
			(stroke
				(width 0.1)
				(type default)
			)
			(layer "F.Fab")
		)
		(fp_line
			(start -0.6858 -0.3048)
			(end -0.1016 -0.3048)
			(stroke
				(width 0.1)
				(type default)
			)
			(layer "F.Fab")
		)
		(fp_line
			(start -0.1016 -0.3048)
			(end -0.1016 -0.2794)
			(stroke
				(width 0.1)
				(type default)
			)
			(layer "F.Fab")
		)
		(fp_line
			(start 0.1016 -0.3048)
			(end 0.6858 -0.3048)
			(stroke
				(width 0.1)
				(type default)
			)
			(layer "F.Fab")
		)
		(fp_line
			(start 0.6858 -0.3048)
			(end 0.6858 0.3048)
			(stroke
				(width 0.1)
				(type default)
			)
			(layer "F.Fab")
		)
		(pad "1" smd rect
			(at -0.40005 0 90)
			(size 0.4572 0.508)
			(layers "F.Cu" "F.Mask" "F.Paste")
			(net "GND")
		)
		(pad "2" smd rect
			(at 0.40005 0 90)
			(size 0.4572 0.508)
			(layers "F.Cu" "F.Mask" "F.Paste")
			(net "P12V_LED_FAN4")
		)
	)
	(footprint ""
		(layer "F.Cu")
		(at 22.479 -116.586 90)
		(property "Reference" "U64"
			(at 0.254 -1.87833 90)
			(unlocked yes)
			(layer "F.SilkS")
			(effects
				(font
					(size 0.7874 0.5842)
					(thickness 0.1524)
				)
				(justify left)
			)
		)
		(property "Value" ""
			(at 0 0 90)
			(layer "F.Fab")
			(effects
				(font
					(size 1.27 1.27)
				)
			)
		)
		(duplicate_pad_numbers_are_jumpers no)
		(fp_line
			(start 1.33096 -1.100074)
			(end 1.33096 1.100074)
			(stroke
				(width 0.1524)
				(type default)
			)
			(layer "F.SilkS")
		)
		(fp_line
			(start 0.381 -1.100074)
			(end 1.33096 -1.100074)
			(stroke
				(width 0.1524)
				(type default)
			)
			(layer "F.SilkS")
		)
		(fp_line
			(start -0.381 -1.100074)
			(end 0 -0.649986)
			(stroke
				(width 0.1524)
				(type default)
			)
			(layer "F.SilkS")
		)
		(fp_line
			(start -1.33096 -1.100074)
			(end -0.381 -1.100074)
			(stroke
				(width 0.1524)
				(type default)
			)
			(layer "F.SilkS")
		)
		(fp_line
			(start 0 -0.649986)
			(end 0.381 -1.100074)
			(stroke
				(width 0.1524)
				(type default)
			)
			(layer "F.SilkS")
		)
		(fp_line
			(start 1.33096 1.100074)
			(end -1.33096 1.100074)
			(stroke
				(width 0.1524)
				(type default)
			)
			(layer "F.SilkS")
		)
		(fp_line
			(start -1.33096 1.100074)
			(end -1.33096 -1.100074)
			(stroke
				(width 0.1524)
				(type default)
			)
			(layer "F.SilkS")
		)
		(fp_poly
			(pts
				(xy -1.77546 -1.967738) (xy -2.134616 -1.608582) (xy -1.41605 -1.249172)
			)
			(stroke
				(width 0)
				(type default)
			)
			(fill yes)
			(layer "F.SilkS")
		)
		(fp_line
			(start 0.674878 -1.100074)
			(end 0.674878 1.100074)
			(stroke
				(width 0.1)
				(type default)
			)
			(layer "F.Fab")
		)
		(fp_line
			(start -0.674878 -1.100074)
			(end 0.674878 -1.100074)
			(stroke
				(width 0.1)
				(type default)
			)
			(layer "F.Fab")
		)
		(fp_line
			(start 0.674878 1.100074)
			(end -0.674878 1.100074)
			(stroke
				(width 0.1)
				(type default)
			)
			(layer "F.Fab")
		)
		(fp_line
			(start -0.674878 1.100074)
			(end -0.674878 -1.100074)
			(stroke
				(width 0.1)
				(type default)
			)
			(layer "F.Fab")
		)
		(fp_poly
			(pts
				(xy -2.209292 -0.902462) (xy -2.209292 -0.394462) (xy -1.447292 -0.648462)
			)
			(stroke
				(width 0)
				(type default)
			)
			(fill yes)
			(layer "F.Fab")
		)
		(pad "1" smd rect
			(at -0.94996 -0.649986 180)
			(size 0.4064 0.508)
			(layers "F.Cu" "F.Mask" "F.Paste")
			(net "NC_U64_P1")
		)
		(pad "2" smd rect
			(at -0.94996 0 180)
			(size 0.4064 0.508)
			(layers "F.Cu" "F.Mask" "F.Paste")
			(net "FAN_2_PWM")
		)
		(pad "3" smd rect
			(at -0.94996 0.649986 180)
			(size 0.4064 0.508)
			(layers "F.Cu" "F.Mask" "F.Paste")
			(net "GND")
		)
		(pad "4" smd rect
			(at 0.94996 0.649986 180)
			(size 0.4064 0.508)
			(layers "F.Cu" "F.Mask" "F.Paste")
			(net "FAN_2_PWM_BUF")
		)
		(pad "5" smd rect
			(at 0.94996 -0.649986 180)
			(size 0.4064 0.508)
			(layers "F.Cu" "F.Mask" "F.Paste")
			(net "P3V3_AUX")
		)
	)
)
